(kicad_pcb
	(version 20241229)
	(generator "pcbnew")
	(generator_version "9.0")
	(general
		(thickness 1.258)
		(legacy_teardrops no)
	)
	(paper "A4")
	(title_block
		(date "2024-05-27")
		(rev "1.1.2")
		(comment 9 "footprints 26-27 of 64")
	)
	(layers
		(0 "F.Cu" signal)
		(4 "In1.Cu" power)
		(6 "In2.Cu" power)
		(8 "In3.Cu" signal)
		(10 "In4.Cu" signal)
		(2 "B.Cu" signal)
		(9 "F.Adhes" user "F.Adhesive")
		(11 "B.Adhes" user "B.Adhesive")
		(13 "F.Paste" user)
		(15 "B.Paste" user)
		(5 "F.SilkS" user "F.Silkscreen")
		(7 "B.SilkS" user "B.Silkscreen")
		(1 "F.Mask" user)
		(3 "B.Mask" user)
		(17 "Dwgs.User" user "User.Drawings")
		(19 "Cmts.User" user "User.Comments")
		(21 "Eco1.User" user "User.Eco1")
		(23 "Eco2.User" user "User.Eco2")
		(25 "Edge.Cuts" user)
		(27 "Margin" user)
		(31 "F.CrtYd" user "F.Courtyard")
		(29 "B.CrtYd" user "B.Courtyard")
		(35 "F.Fab" user)
		(33 "B.Fab" user)
	)
	(footprint "antmicro-footprints:FB_0805_2012Metric"
		(layer "F.Cu")
		(at 138.2 85.2)
		(descr "FERRITE BEAD 0805")
		(tags "FERRITE BEAD 0805")
		(property "Reference" "FB2"
			(at 1.81 0.41 0)
			(layer "F.SilkS")
			(effects
				(font
					(size 0.7 0.7)
					(thickness 0.15)
				)
				(justify left bottom)
			)
		)
		(property "Value" "FB_220Z_1.5A_WE-CBF_0805"
			(at 0 1.8 0)
			(layer "F.Fab")
			(hide yes)
			(effects
				(font
					(size 0.7 0.7)
					(thickness 0.15)
				)
				(justify left bottom)
			)
		)
		(property "Description" "Ferrite Bead, 0805 [2012 Metric], 220 ohm, 2 A, WE-CBF, 0.05 ohm, ± 25%, High Current"
			(at 0 0 0)
			(layer "F.Fab")
			(hide yes)
			(effects
				(font
					(size 1.27 1.27)
					(thickness 0.15)
				)
			)
		)
		(property "Author" "Antmicro"
			(at 0 0 0)
			(layer "F.Fab")
			(hide yes)
			(effects
				(font
					(size 1 1)
					(thickness 0.15)
				)
			)
		)
		(property "Current" "1.5A"
			(at 0 0 0)
			(layer "F.Fab")
			(hide yes)
			(effects
				(font
					(size 1 1)
					(thickness 0.15)
				)
			)
		)
		(property "License" "Apache-2.0"
			(at 0 0 0)
			(layer "F.Fab")
			(hide yes)
			(effects
				(font
					(size 1 1)
					(thickness 0.15)
				)
			)
		)
		(property "MPN" "742792022"
			(at 0 0 0)
			(layer "F.Fab")
			(hide yes)
			(effects
				(font
					(size 1 1)
					(thickness 0.15)
				)
			)
		)
		(property "Manufacturer" "Würth Elektronik"
			(at 0 0 0)
			(layer "F.Fab")
			(hide yes)
			(effects
				(font
					(size 1 1)
					(thickness 0.15)
				)
			)
		)
		(property "Public" "False"
			(at 0 0 0)
			(layer "F.Fab")
			(hide yes)
			(effects
				(font
					(size 1 1)
					(thickness 0.15)
				)
			)
		)
		(property "Val" "220Z/1.5A"
			(at 0 0 0)
			(layer "F.Fab")
			(hide yes)
			(effects
				(font
					(size 1 1)
					(thickness 0.15)
				)
			)
		)
		(sheetname "DDR5")
		(sheetfile "ddr5.kicad_sch")
		(attr smd)
		(fp_line
			(start -0.319 0.698)
			(end 0.281 0.698)
			(stroke
				(width 0.15)
				(type solid)
			)
			(layer "F.SilkS")
		)
		(fp_line
			(start -0.299 -0.698)
			(end 0.299 -0.698)
			(stroke
				(width 0.15)
				(type solid)
			)
			(layer "F.SilkS")
		)
		(fp_rect
			(start 1.95 -0.9)
			(end -1.95 0.9)
			(stroke
				(width 0.05)
				(type default)
			)
			(fill no)
			(layer "F.CrtYd")
		)
		(fp_line
			(start -0.948 -0.681)
			(end 0.948 -0.681)
			(stroke
				(width 0.15)
				(type solid)
			)
			(layer "F.Fab")
		)
		(fp_line
			(start -0.948 -0.676)
			(end -0.948 0.676)
			(stroke
				(width 0.15)
				(type solid)
			)
			(layer "F.Fab")
		)
		(fp_line
			(start -0.948 0.681)
			(end 0.948 0.681)
			(stroke
				(width 0.15)
				(type solid)
			)
			(layer "F.Fab")
		)
		(fp_line
			(start 0.948 -0.676)
			(end 0.948 0.676)
			(stroke
				(width 0.15)
				(type solid)
			)
			(layer "F.Fab")
		)
		(pad "1" smd roundrect
			(at -1.1 0)
			(size 1.2 1.3)
			(layers "F.Cu" "F.Mask" "F.Paste")
			(roundrect_rratio 0.25)
			(net 50 "1V8_SYS")
			(pintype "passive")
		)
		(pad "2" smd roundrect
			(at 1.1 0)
			(size 1.2 1.3)
			(layers "F.Cu" "F.Mask" "F.Paste")
			(roundrect_rratio 0.25)
			(net 19 "VPP")
			(pintype "passive")
		)
	)
	(footprint "antmicro-footprints:FB_0805_2012Metric"
		(layer "F.Cu")
		(at 138.2 89.2)
		(descr "FERRITE BEAD 0805")
		(tags "FERRITE BEAD 0805")
		(property "Reference" "FB3"
			(at 1.81 0.41 0)
			(layer "F.SilkS")
			(effects
				(font
					(size 0.7 0.7)
					(thickness 0.15)
				)
				(justify left bottom)
			)
		)
		(property "Value" "FB_220Z_1.5A_WE-CBF_0805"
			(at 0 1.8 0)
			(layer "F.Fab")
			(hide yes)
			(effects
				(font
					(size 0.7 0.7)
					(thickness 0.15)
				)
				(justify left bottom)
			)
		)
		(property "Description" "Ferrite Bead, 0805 [2012 Metric], 220 ohm, 2 A, WE-CBF, 0.05 ohm, ± 25%, High Current"
			(at 0 0 0)
			(layer "F.Fab")
			(hide yes)
			(effects
				(font
					(size 1.27 1.27)
					(thickness 0.15)
				)
			)
		)
		(property "Author" "Antmicro"
			(at 0 0 0)
			(layer "F.Fab")
			(hide yes)
			(effects
				(font
					(size 1 1)
					(thickness 0.15)
				)
			)
		)
		(property "Current" "1.5A"
			(at 0 0 0)
			(layer "F.Fab")
			(hide yes)
			(effects
				(font
					(size 1 1)
					(thickness 0.15)
				)
			)
		)
		(property "License" "Apache-2.0"
			(at 0 0 0)
			(layer "F.Fab")
			(hide yes)
			(effects
				(font
					(size 1 1)
					(thickness 0.15)
				)
			)
		)
		(property "MPN" "742792022"
			(at 0 0 0)
			(layer "F.Fab")
			(hide yes)
			(effects
				(font
					(size 1 1)
					(thickness 0.15)
				)
			)
		)
		(property "Manufacturer" "Würth Elektronik"
			(at 0 0 0)
			(layer "F.Fab")
			(hide yes)
			(effects
				(font
					(size 1 1)
					(thickness 0.15)
				)
			)
		)
		(property "Public" "False"
			(at 0 0 0)
			(layer "F.Fab")
			(hide yes)
			(effects
				(font
					(size 1 1)
					(thickness 0.15)
				)
			)
		)
		(property "Val" "220Z/1.5A"
			(at 0 0 0)
			(layer "F.Fab")
			(hide yes)
			(effects
				(font
					(size 1 1)
					(thickness 0.15)
				)
			)
		)
		(sheetname "DDR5")
		(sheetfile "ddr5.kicad_sch")
		(attr smd)
		(fp_line
			(start -0.319 0.698)
			(end 0.281 0.698)
			(stroke
				(width 0.15)
				(type solid)
			)
			(layer "F.SilkS")
		)
		(fp_line
			(start -0.299 -0.698)
			(end 0.299 -0.698)
			(stroke
				(width 0.15)
				(type solid)
			)
			(layer "F.SilkS")
		)
		(fp_rect
			(start 1.95 -0.9)
			(end -1.95 0.9)
			(stroke
				(width 0.05)
				(type default)
			)
			(fill no)
			(layer "F.CrtYd")
		)
		(fp_line
			(start -0.948 -0.681)
			(end 0.948 -0.681)
			(stroke
				(width 0.15)
				(type solid)
			)
			(layer "F.Fab")
		)
		(fp_line
			(start -0.948 -0.676)
			(end -0.948 0.676)
			(stroke
				(width 0.15)
				(type solid)
			)
			(layer "F.Fab")
		)
		(fp_line
			(start -0.948 0.681)
			(end 0.948 0.681)
			(stroke
				(width 0.15)
				(type solid)
			)
			(layer "F.Fab")
		)
		(fp_line
			(start 0.948 -0.676)
			(end 0.948 0.676)
			(stroke
				(width 0.15)
				(type solid)
			)
			(layer "F.Fab")
		)
		(pad "1" smd roundrect
			(at -1.1 0)
			(size 1.2 1.3)
			(layers "F.Cu" "F.Mask" "F.Paste")
			(roundrect_rratio 0.25)
			(net 51 "1V1_SYS")
			(pintype "passive")
		)
		(pad "2" smd roundrect
			(at 1.1 0)
			(size 1.2 1.3)
			(layers "F.Cu" "F.Mask" "F.Paste")
			(roundrect_rratio 0.25)
			(net 2 "VDDQ")
			(pintype "passive")
		)
	)
)
